# T6G (Grand Teton) — schematic netlist excerpt (pin names and nets, part order shuffled) for the footprints in the layout excerpt that follows; sources: Cadence DE-HDL packaged netlist, KiCad conversion of 04192023_DAF0TMB3IC0_F0TG_MB_C_brd_V02_OCP.brd

R6052  Q_RES  0 5% CHIP  pkg 0402LF  page 82 : A = E1S_0_PRSNT_R_N ; B = E1S_0_PRSNT_N
C370  Q_CAP  10UF 6.3V 20% X6S  pkg C0402  page 345 : A = P1V8_CPU1_RT_1D ; B = GND

(kicad_pcb
	(version 20260206)
	(generator "pcbnew")
	(generator_version "10.0")
	(general
		(thickness 1.6)
		(legacy_teardrops no)
	)
	(paper "A4")
	(title_block
		(title "04192023_DAF0TMB3IC0_F0TG_MB_C_brd_V02_OCP.brd")
		(comment 1 "Grand Teton / footprints 3376-3377 of 8354")
	)
	(layers
		(0 "F.Cu" signal "TOP")
		(4 "In1.Cu" signal "GND")
		(6 "In2.Cu" signal "IN1")
		(8 "In3.Cu" signal "GND1")
		(10 "In4.Cu" signal "IN2")
		(12 "In5.Cu" signal "GND2")
		(14 "In6.Cu" signal "IN3")
		(16 "In7.Cu" signal "GND3")
		(18 "In8.Cu" signal "VCC")
		(20 "In9.Cu" signal "VCC1")
		(22 "In10.Cu" signal "GND4")
		(24 "In11.Cu" signal "IN4")
		(26 "In12.Cu" signal "GND5")
		(28 "In13.Cu" signal "IN5")
		(30 "In14.Cu" signal "GND6")
		(32 "In15.Cu" signal "IN6")
		(34 "In16.Cu" signal "GND7")
		(2 "B.Cu" signal "BOTTOM")
		(9 "F.Adhes" user "F.Adhesive")
		(11 "B.Adhes" user "B.Adhesive")
		(13 "F.Paste" user "Package Geometry/Pastemask Top")
		(15 "B.Paste" user "Package Geometry/Pastemask Bottom")
		(5 "F.SilkS" user "Ref Des/Silkscreen Top")
		(7 "B.SilkS" user "Ref Des/Silkscreen Bottom")
		(1 "F.Mask" user "Board Geometry/Soldermask Top")
		(3 "B.Mask" user "Board Geometry/Soldermask Bottom")
		(17 "Dwgs.User" user "User.Drawings")
		(19 "Cmts.User" user "User.Comments")
		(21 "Eco1.User" user "User.Eco1")
		(23 "Eco2.User" user "User.Eco2")
		(25 "Edge.Cuts" user "Board Geometry/Outline")
		(27 "Margin" user)
		(31 "F.CrtYd" user "Package Geometry/Place Bound Top")
		(29 "B.CrtYd" user "Package Geometry/Place Bound Bottom")
		(35 "F.Fab" user "Ref Des/Assembly Top")
		(33 "B.Fab" user "Ref Des/Assembly Bottom")
	)
	(footprint ""
		(layer "F.Cu")
		(at 173.171358 -387.737604)
		(property "Reference" "C370"
			(at 0 0 0)
			(layer "F.SilkS")
			(hide yes)
			(effects
				(font
					(size 1.27 1.27)
				)
			)
		)
		(property "Value" ""
			(at 0 0 0)
			(layer "F.Fab")
			(effects
				(font
					(size 1.27 1.27)
				)
			)
		)
		(duplicate_pad_numbers_are_jumpers no)
		(fp_line
			(start -0.7874 -0.4064)
			(end 0.7874 -0.4064)
			(stroke
				(width 0.1524)
				(type default)
			)
			(layer "F.SilkS")
		)
		(fp_line
			(start -0.7874 0.4064)
			(end -0.7874 -0.4064)
			(stroke
				(width 0.1524)
				(type default)
			)
			(layer "F.SilkS")
		)
		(fp_line
			(start 0.7874 -0.4064)
			(end 0.7874 0.4064)
			(stroke
				(width 0.1524)
				(type default)
			)
			(layer "F.SilkS")
		)
		(fp_line
			(start 0.7874 0.4064)
			(end -0.7874 0.4064)
			(stroke
				(width 0.1524)
				(type default)
			)
			(layer "F.SilkS")
		)
		(fp_line
			(start -0.67945 -0.305054)
			(end -0.12065 -0.305054)
			(stroke
				(width 0.1)
				(type default)
			)
			(layer "F.Fab")
		)
		(fp_line
			(start -0.67945 0.3048)
			(end -0.67945 -0.305054)
			(stroke
				(width 0.1)
				(type default)
			)
			(layer "F.Fab")
		)
		(fp_line
			(start -0.12065 -0.305054)
			(end -0.12065 -0.2794)
			(stroke
				(width 0.1)
				(type default)
			)
			(layer "F.Fab")
		)
		(fp_line
			(start -0.12065 -0.2794)
			(end 0.12065 -0.2794)
			(stroke
				(width 0.1)
				(type default)
			)
			(layer "F.Fab")
		)
		(fp_line
			(start -0.12065 0.2794)
			(end -0.12065 0.3048)
			(stroke
				(width 0.1)
				(type default)
			)
			(layer "F.Fab")
		)
		(fp_line
			(start -0.12065 0.3048)
			(end -0.67945 0.3048)
			(stroke
				(width 0.1)
				(type default)
			)
			(layer "F.Fab")
		)
		(fp_line
			(start 0.120396 0.2794)
			(end -0.12065 0.2794)
			(stroke
				(width 0.1)
				(type default)
			)
			(layer "F.Fab")
		)
		(fp_line
			(start 0.120396 0.3048)
			(end 0.120396 0.2794)
			(stroke
				(width 0.1)
				(type default)
			)
			(layer "F.Fab")
		)
		(fp_line
			(start 0.12065 -0.3048)
			(end 0.67945 -0.3048)
			(stroke
				(width 0.1)
				(type default)
			)
			(layer "F.Fab")
		)
		(fp_line
			(start 0.12065 -0.2794)
			(end 0.12065 -0.3048)
			(stroke
				(width 0.1)
				(type default)
			)
			(layer "F.Fab")
		)
		(fp_line
			(start 0.67945 -0.3048)
			(end 0.67945 0.3048)
			(stroke
				(width 0.1)
				(type default)
			)
			(layer "F.Fab")
		)
		(fp_line
			(start 0.67945 0.3048)
			(end 0.120396 0.3048)
			(stroke
				(width 0.1)
				(type default)
			)
			(layer "F.Fab")
		)
		(pad "1" smd circle
			(at -0.40005 0)
			(size 0 0)
			(layers "F.Cu" "F.Mask" "F.Paste")
			(net "P1V8_CPU1_RT_1D")
		)
		(pad "2" smd circle
			(at 0.40005 0)
			(size 0 0)
			(layers "F.Cu" "F.Mask" "F.Paste")
			(net "GND")
		)
	)
	(footprint ""
		(layer "F.Cu")
		(at 192.786 -92.801948 -90)
		(property "Reference" "R6052"
			(at 0 0 270)
			(layer "F.SilkS")
			(hide yes)
			(effects
				(font
					(size 1.27 1.27)
				)
			)
		)
		(property "Value" ""
			(at 0 0 270)
			(layer "F.Fab")
			(effects
				(font
					(size 1.27 1.27)
				)
			)
		)
		(duplicate_pad_numbers_are_jumpers no)
		(fp_line
			(start -0.7874 0.4064)
			(end -0.7874 -0.4064)
			(stroke
				(width 0.1524)
				(type default)
			)
			(layer "F.SilkS")
		)
		(fp_line
			(start 0.7874 0.4064)
			(end -0.7874 0.4064)
			(stroke
				(width 0.1524)
				(type default)
			)
			(layer "F.SilkS")
		)
		(fp_line
			(start -0.7874 -0.4064)
			(end 0.7874 -0.4064)
			(stroke
				(width 0.1524)
				(type default)
			)
			(layer "F.SilkS")
		)
		(fp_line
			(start 0.7874 -0.4064)
			(end 0.7874 0.4064)
			(stroke
				(width 0.1524)
				(type default)
			)
			(layer "F.SilkS")
		)
		(fp_line
			(start -0.67945 0.3048)
			(end -0.67945 -0.305054)
			(stroke
				(width 0.1)
				(type default)
			)
			(layer "F.Fab")
		)
		(fp_line
			(start -0.12065 0.3048)
			(end -0.67945 0.3048)
			(stroke
				(width 0.1)
				(type default)
			)
			(layer "F.Fab")
		)
		(fp_line
			(start 0.120396 0.3048)
			(end 0.120396 0.2794)
			(stroke
				(width 0.1)
				(type default)
			)
			(layer "F.Fab")
		)
		(fp_line
			(start 0.67945 0.3048)
			(end 0.120396 0.3048)
			(stroke
				(width 0.1)
				(type default)
			)
			(layer "F.Fab")
		)
		(fp_line
			(start -0.12065 0.2794)
			(end -0.12065 0.3048)
			(stroke
				(width 0.1)
				(type default)
			)
			(layer "F.Fab")
		)
		(fp_line
			(start 0.120396 0.2794)
			(end -0.12065 0.2794)
			(stroke
				(width 0.1)
				(type default)
			)
			(layer "F.Fab")
		)
		(fp_line
			(start -0.12065 -0.2794)
			(end 0.12065 -0.2794)
			(stroke
				(width 0.1)
				(type default)
			)
			(layer "F.Fab")
		)
		(fp_line
			(start 0.12065 -0.2794)
			(end 0.12065 -0.3048)
			(stroke
				(width 0.1)
				(type default)
			)
			(layer "F.Fab")
		)
		(fp_line
			(start 0.12065 -0.3048)
			(end 0.67945 -0.3048)
			(stroke
				(width 0.1)
				(type default)
			)
			(layer "F.Fab")
		)
		(fp_line
			(start 0.67945 -0.3048)
			(end 0.67945 0.3048)
			(stroke
				(width 0.1)
				(type default)
			)
			(layer "F.Fab")
		)
		(fp_line
			(start -0.67945 -0.305054)
			(end -0.12065 -0.305054)
			(stroke
				(width 0.1)
				(type default)
			)
			(layer "F.Fab")
		)
		(fp_line
			(start -0.12065 -0.305054)
			(end -0.12065 -0.2794)
			(stroke
				(width 0.1)
				(type default)
			)
			(layer "F.Fab")
		)
		(pad "1" smd circle
			(at -0.40005 0 270)
			(size 0 0)
			(layers "F.Cu" "F.Mask" "F.Paste")
			(net "E1S_0_PRSNT_R_N")
		)
		(pad "2" smd circle
			(at 0.40005 0 270)
			(size 0 0)
			(layers "F.Cu" "F.Mask" "F.Paste")
			(net "E1S_0_PRSNT_N")
		)
	)
)
